(kicad_pcb
	(version 20260206)
	(generator "pcbnew")
	(generator_version "10.0")
	(general
		(thickness 1.6)
		(legacy_teardrops no)
	)
	(paper "A4")
	(title_block
		(title "Wiwynn_Tioga_Pass_MB.brd")
		(comment 1 "Tioga Pass / footprints 1425-1432 of 4770")
	)
	(layers
		(0 "F.Cu" signal "TOP")
		(4 "In1.Cu" signal "L2GND")
		(6 "In2.Cu" signal "L3")
		(8 "In3.Cu" signal "L4GND")
		(10 "In4.Cu" signal "L5")
		(12 "In5.Cu" signal "L6GND")
		(14 "In6.Cu" signal "L7VCC")
		(16 "In7.Cu" signal "L8VCC")
		(18 "In8.Cu" signal "L9GND")
		(20 "In9.Cu" signal "L10")
		(22 "In10.Cu" signal "L11GND")
		(24 "In11.Cu" signal "L12")
		(26 "In12.Cu" signal "L13GND")
		(2 "B.Cu" signal "BOTTOM")
		(9 "F.Adhes" user "F.Adhesive")
		(11 "B.Adhes" user "B.Adhesive")
		(13 "F.Paste" user "Package Geometry/Pastemask Top")
		(15 "B.Paste" user "Package Geometry/Pastemask Bottom")
		(5 "F.SilkS" user "Ref Des/Silkscreen Top")
		(7 "B.SilkS" user "Ref Des/Silkscreen Bottom")
		(1 "F.Mask" user "Board Geometry/Soldermask Top")
		(3 "B.Mask" user "Board Geometry/Soldermask Bottom")
		(17 "Dwgs.User" user "User.Drawings")
		(19 "Cmts.User" user "User.Comments")
		(21 "Eco1.User" user "User.Eco1")
		(23 "Eco2.User" user "User.Eco2")
		(25 "Edge.Cuts" user "Board Geometry/Outline")
		(27 "Margin" user)
		(31 "F.CrtYd" user "Package Geometry/Place Bound Top")
		(29 "B.CrtYd" user "Package Geometry/Place Bound Bottom")
		(35 "F.Fab" user "Ref Des/Assembly Top")
		(33 "B.Fab" user "Ref Des/Assembly Bottom")
	)
	(footprint ""
		(layer "F.Cu")
		(at 482.00056 -34.6964 180)
		(property "Reference" "C8F19"
			(at -0.8382 -0.67818 180)
			(unlocked yes)
			(layer "F.SilkS")
			(effects
				(font
					(size 0.4064 0.254)
					(thickness 0.1524)
				)
				(justify left)
			)
		)
		(property "Value" ""
			(at 0 0 180)
			(layer "F.Fab")
			(effects
				(font
					(size 1.27 1.27)
				)
			)
		)
		(duplicate_pad_numbers_are_jumpers no)
		(fp_poly
			(pts
				(xy 0.3048 -0.1016) (xy 0.3048 0.9906) (xy -0.3048 0.9906) (xy -0.3048 -0.1016)
			)
			(stroke
				(width 0)
				(type default)
			)
			(fill no)
			(layer "F.CrtYd")
		)
		(fp_line
			(start 0.3048 0.9906)
			(end 0.3048 -0.1016)
			(stroke
				(width 0.1)
				(type default)
			)
			(layer "F.Fab")
		)
		(fp_line
			(start 0.3048 -0.1016)
			(end -0.3048 -0.1016)
			(stroke
				(width 0.1)
				(type default)
			)
			(layer "F.Fab")
		)
		(fp_line
			(start -0.3048 0.9906)
			(end 0.3048 0.9906)
			(stroke
				(width 0.1)
				(type default)
			)
			(layer "F.Fab")
		)
		(fp_line
			(start -0.3048 -0.1016)
			(end -0.3048 0.9906)
			(stroke
				(width 0.1)
				(type default)
			)
			(layer "F.Fab")
		)
		(pad "1" smd rect
			(at 0 0 180)
			(size 0.508 0.508)
			(layers "F.Cu" "F.Mask" "F.Paste")
			(net "XTAL_CK_MNG_OUT")
		)
		(pad "2" smd rect
			(at 0 0.889 180)
			(size 0.508 0.508)
			(layers "F.Cu" "F.Mask" "F.Paste")
			(net "GND")
		)
		(zone
			(layer "F.Cu")
			(hatch none 0.5)
			(connect_pads
				(clearance 0)
			)
			(min_thickness 0.25)
			(keepout
				(tracks not_allowed)
				(vias allowed)
				(pads allowed)
				(copperpour not_allowed)
				(footprints allowed)
			)
			(placement
				(enabled no)
				(sheetname "")
			)
			(fill
				(thermal_gap 0.5)
				(thermal_bridge_width 0.5)
				(island_removal_mode 0)
			)
			(polygon
				(pts
					(xy 482.25456 -35.3314) (xy 481.74656 -35.3314) (xy 481.74656 -34.9504) (xy 482.25456 -34.9504)
				)
			)
		)
		(zone
			(layer "F.Cu")
			(hatch none 0.5)
			(connect_pads
				(clearance 0)
			)
			(min_thickness 0.25)
			(keepout
				(tracks allowed)
				(vias not_allowed)
				(pads allowed)
				(copperpour not_allowed)
				(footprints allowed)
			)
			(placement
				(enabled no)
				(sheetname "")
			)
			(fill
				(thermal_gap 0.5)
				(thermal_bridge_width 0.5)
				(island_removal_mode 0)
			)
			(polygon
				(pts
					(xy 482.25456 -34.9504) (xy 481.74656 -34.9504) (xy 481.74656 -35.3314) (xy 482.25456 -35.3314)
				)
			)
		)
	)
	(footprint ""
		(layer "F.Cu")
		(at 340.775036 -26.973276)
		(property "Reference" "R7F8"
			(at 1.01473 0.656336 270)
			(unlocked yes)
			(layer "F.SilkS")
			(effects
				(font
					(size 0.4064 0.254)
					(thickness 0.1524)
				)
			)
		)
		(property "Value" ""
			(at 0 0 0)
			(layer "F.Fab")
			(effects
				(font
					(size 1.27 1.27)
				)
			)
		)
		(duplicate_pad_numbers_are_jumpers no)
		(fp_poly
			(pts
				(xy -0.4953 -0.2032) (xy 0.4953 -0.2032) (xy 0.4953 1.6002) (xy -0.4953 1.6002)
			)
			(stroke
				(width 0)
				(type default)
			)
			(fill no)
			(layer "F.CrtYd")
		)
		(fp_line
			(start -0.4953 -0.2032)
			(end 0.4953 -0.2032)
			(stroke
				(width 0.1)
				(type default)
			)
			(layer "F.Fab")
		)
		(fp_line
			(start -0.4953 1.6002)
			(end -0.4953 -0.2032)
			(stroke
				(width 0.1)
				(type default)
			)
			(layer "F.Fab")
		)
		(fp_line
			(start 0.4953 -0.2032)
			(end 0.4953 1.6002)
			(stroke
				(width 0.1)
				(type default)
			)
			(layer "F.Fab")
		)
		(fp_line
			(start 0.4953 1.6002)
			(end -0.4953 1.6002)
			(stroke
				(width 0.1)
				(type default)
			)
			(layer "F.Fab")
		)
		(pad "1" smd rect
			(at 0 0)
			(size 0.762 0.889)
			(layers "F.Cu" "F.Mask" "F.Paste")
			(net "VR_PVPP_ABC_BOOT")
		)
		(pad "2" smd rect
			(at 0 1.397)
			(size 0.762 0.889)
			(layers "F.Cu" "F.Mask" "F.Paste")
			(net "VR_PVPP_ABC_BOOT_R")
		)
		(zone
			(layer "F.Cu")
			(hatch none 0.5)
			(connect_pads
				(clearance 0)
			)
			(min_thickness 0.25)
			(keepout
				(tracks not_allowed)
				(vias allowed)
				(pads allowed)
				(copperpour not_allowed)
				(footprints allowed)
			)
			(placement
				(enabled no)
				(sheetname "")
			)
			(fill
				(thermal_gap 0.5)
				(thermal_bridge_width 0.5)
				(island_removal_mode 0)
			)
			(polygon
				(pts
					(xy 340.394036 -26.020776) (xy 341.156036 -26.020776) (xy 341.156036 -26.528776) (xy 340.394036 -26.528776)
				)
			)
		)
		(zone
			(layer "F.Cu")
			(hatch none 0.5)
			(connect_pads
				(clearance 0)
			)
			(min_thickness 0.25)
			(keepout
				(tracks allowed)
				(vias not_allowed)
				(pads allowed)
				(copperpour not_allowed)
				(footprints allowed)
			)
			(placement
				(enabled no)
				(sheetname "")
			)
			(fill
				(thermal_gap 0.5)
				(thermal_bridge_width 0.5)
				(island_removal_mode 0)
			)
			(polygon
				(pts
					(xy 341.156036 -26.020776) (xy 341.156036 -26.528776) (xy 340.394036 -26.528776) (xy 340.394036 -26.020776)
				)
			)
		)
	)
	(footprint ""
		(layer "F.Cu")
		(at -0.27432 -15.3924)
		(property "Reference" "R1G25"
			(at -0.8382 -0.67818 0)
			(unlocked yes)
			(layer "F.SilkS")
			(effects
				(font
					(size 0.4064 0.254)
					(thickness 0.1524)
				)
				(justify left)
			)
		)
		(property "Value" ""
			(at 0 0 0)
			(layer "F.Fab")
			(effects
				(font
					(size 1.27 1.27)
				)
			)
		)
		(duplicate_pad_numbers_are_jumpers no)
		(fp_rect
			(start -0.2794 0.9906)
			(end 0.2794 -0.1016)
			(stroke
				(width 0)
				(type default)
			)
			(fill no)
			(layer "F.CrtYd")
		)
		(fp_line
			(start -0.2794 -0.1016)
			(end -0.2794 0.9906)
			(stroke
				(width 0.1)
				(type default)
			)
			(layer "F.Fab")
		)
		(fp_line
			(start -0.2794 0.9906)
			(end 0.2794 0.9906)
			(stroke
				(width 0.1)
				(type default)
			)
			(layer "F.Fab")
		)
		(fp_line
			(start 0.2794 -0.1016)
			(end -0.2794 -0.1016)
			(stroke
				(width 0.1)
				(type default)
			)
			(layer "F.Fab")
		)
		(fp_line
			(start 0.2794 0.9906)
			(end 0.2794 -0.1016)
			(stroke
				(width 0.1)
				(type default)
			)
			(layer "F.Fab")
		)
		(pad "1" smd rect
			(at 0 0)
			(size 0.508 0.508)
			(layers "F.Cu" "F.Mask" "F.Paste")
			(net "VR_PVDDQ_GHJ_PH2_OCSET")
		)
		(pad "2" smd rect
			(at 0 0.889)
			(size 0.508 0.508)
			(layers "F.Cu" "F.Mask" "F.Paste")
			(net "GND")
		)
		(zone
			(layer "F.Cu")
			(hatch none 0.5)
			(connect_pads
				(clearance 0)
			)
			(min_thickness 0.25)
			(keepout
				(tracks not_allowed)
				(vias allowed)
				(pads allowed)
				(copperpour not_allowed)
				(footprints allowed)
			)
			(placement
				(enabled no)
				(sheetname "")
			)
			(fill
				(thermal_gap 0.5)
				(thermal_bridge_width 0.5)
				(island_removal_mode 0)
			)
			(polygon
				(pts
					(xy -0.52832 -14.7574) (xy -0.02032 -14.7574) (xy -0.02032 -15.1384) (xy -0.52832 -15.1384)
				)
			)
		)
		(zone
			(layer "F.Cu")
			(hatch none 0.5)
			(connect_pads
				(clearance 0)
			)
			(min_thickness 0.25)
			(keepout
				(tracks allowed)
				(vias not_allowed)
				(pads allowed)
				(copperpour not_allowed)
				(footprints allowed)
			)
			(placement
				(enabled no)
				(sheetname "")
			)
			(fill
				(thermal_gap 0.5)
				(thermal_bridge_width 0.5)
				(island_removal_mode 0)
			)
			(polygon
				(pts
					(xy -0.52832 -14.7574) (xy -0.02032 -14.7574) (xy -0.02032 -15.1384) (xy -0.52832 -15.1384)
				)
			)
		)
	)
	(footprint ""
		(layer "F.Cu")
		(at 8.993378 4.911598 -90)
		(property "Reference" "R1G23"
			(at 0 0 270)
			(layer "F.SilkS")
			(hide yes)
			(effects
				(font
					(size 1.27 1.27)
				)
			)
		)
		(property "Value" ""
			(at 0 0 270)
			(layer "F.Fab")
			(effects
				(font
					(size 1.27 1.27)
				)
			)
		)
		(duplicate_pad_numbers_are_jumpers no)
		(fp_poly
			(pts
				(xy -0.2794 -0.1016) (xy 0.2794 -0.1016) (xy 0.2794 0.9906) (xy -0.2794 0.9906)
			)
			(stroke
				(width 0)
				(type default)
			)
			(fill no)
			(layer "F.CrtYd")
		)
		(fp_line
			(start -0.2794 0.9906)
			(end 0.2794 0.9906)
			(stroke
				(width 0.1)
				(type default)
			)
			(layer "F.Fab")
		)
		(fp_line
			(start 0.2794 0.9906)
			(end 0.2794 -0.1016)
			(stroke
				(width 0.1)
				(type default)
			)
			(layer "F.Fab")
		)
		(fp_line
			(start -0.2794 -0.1016)
			(end -0.2794 0.9906)
			(stroke
				(width 0.1)
				(type default)
			)
			(layer "F.Fab")
		)
		(fp_line
			(start 0.2794 -0.1016)
			(end -0.2794 -0.1016)
			(stroke
				(width 0.1)
				(type default)
			)
			(layer "F.Fab")
		)
		(pad "1" smd rect
			(at 0 0 270)
			(size 0.508 0.508)
			(layers "F.Cu" "F.Mask" "F.Paste")
			(net "VR_PVDDQ_GHJ_XADDR1")
		)
		(pad "2" smd rect
			(at 0 0.889 270)
			(size 0.508 0.508)
			(layers "F.Cu" "F.Mask" "F.Paste")
			(net "GND")
		)
		(zone
			(layer "F.Cu")
			(hatch none 0.5)
			(connect_pads
				(clearance 0)
			)
			(min_thickness 0.25)
			(keepout
				(tracks not_allowed)
				(vias allowed)
				(pads allowed)
				(copperpour not_allowed)
				(footprints allowed)
			)
			(placement
				(enabled no)
				(sheetname "")
			)
			(fill
				(thermal_gap 0.5)
				(thermal_bridge_width 0.5)
				(island_removal_mode 0)
			)
			(polygon
				(pts
					(xy 8.358378 4.657598) (xy 8.358378 5.165598) (xy 8.739378 5.165598) (xy 8.739378 4.657598)
				)
			)
		)
		(zone
			(layer "F.Cu")
			(hatch none 0.5)
			(connect_pads
				(clearance 0)
			)
			(min_thickness 0.25)
			(keepout
				(tracks allowed)
				(vias not_allowed)
				(pads allowed)
				(copperpour not_allowed)
				(footprints allowed)
			)
			(placement
				(enabled no)
				(sheetname "")
			)
			(fill
				(thermal_gap 0.5)
				(thermal_bridge_width 0.5)
				(island_removal_mode 0)
			)
			(polygon
				(pts
					(xy 8.739378 4.657598) (xy 8.739378 5.165598) (xy 8.358378 5.165598) (xy 8.358378 4.657598)
				)
			)
		)
	)
	(footprint ""
		(layer "F.Cu")
		(at 435.5719 -19.755612)
		(property "Reference" "R25W142"
			(at -0.8382 -0.67818 0)
			(unlocked yes)
			(layer "F.SilkS")
			(effects
				(font
					(size 0.4064 0.254)
					(thickness 0.1524)
				)
				(justify left)
			)
		)
		(property "Value" ""
			(at 0 0 0)
			(layer "F.Fab")
			(effects
				(font
					(size 1.27 1.27)
				)
			)
		)
		(duplicate_pad_numbers_are_jumpers no)
		(fp_poly
			(pts
				(xy -0.2794 -0.1016) (xy 0.2794 -0.1016) (xy 0.2794 0.9906) (xy -0.2794 0.9906)
			)
			(stroke
				(width 0)
				(type default)
			)
			(fill no)
			(layer "F.CrtYd")
		)
		(fp_line
			(start -0.2794 -0.1016)
			(end -0.2794 0.9906)
			(stroke
				(width 0.1)
				(type default)
			)
			(layer "F.Fab")
		)
		(fp_line
			(start -0.2794 0.9906)
			(end 0.2794 0.9906)
			(stroke
				(width 0.1)
				(type default)
			)
			(layer "F.Fab")
		)
		(fp_line
			(start 0.2794 -0.1016)
			(end -0.2794 -0.1016)
			(stroke
				(width 0.1)
				(type default)
			)
			(layer "F.Fab")
		)
		(fp_line
			(start 0.2794 0.9906)
			(end 0.2794 -0.1016)
			(stroke
				(width 0.1)
				(type default)
			)
			(layer "F.Fab")
		)
		(pad "1" smd rect
			(at 0 0)
			(size 0.508 0.508)
			(layers "F.Cu" "F.Mask" "F.Paste")
			(net "PUMP_TACH1")
		)
		(pad "2" smd rect
			(at 0 0.889)
			(size 0.508 0.508)
			(layers "F.Cu" "F.Mask" "F.Paste")
			(net "GND")
		)
		(zone
			(layer "F.Cu")
			(hatch none 0.5)
			(connect_pads
				(clearance 0)
			)
			(min_thickness 0.25)
			(keepout
				(tracks allowed)
				(vias not_allowed)
				(pads allowed)
				(copperpour not_allowed)
				(footprints allowed)
			)
			(placement
				(enabled no)
				(sheetname "")
			)
			(fill
				(thermal_gap 0.5)
				(thermal_bridge_width 0.5)
				(island_removal_mode 0)
			)
			(polygon
				(pts
					(xy 435.3179 -19.501612) (xy 435.8259 -19.501612) (xy 435.8259 -19.120612) (xy 435.3179 -19.120612)
				)
			)
		)
		(zone
			(layer "F.Cu")
			(hatch none 0.5)
			(connect_pads
				(clearance 0)
			)
			(min_thickness 0.25)
			(keepout
				(tracks not_allowed)
				(vias allowed)
				(pads allowed)
				(copperpour not_allowed)
				(footprints allowed)
			)
			(placement
				(enabled no)
				(sheetname "")
			)
			(fill
				(thermal_gap 0.5)
				(thermal_bridge_width 0.5)
				(island_removal_mode 0)
			)
			(polygon
				(pts
					(xy 435.3179 -19.120612) (xy 435.8259 -19.120612) (xy 435.8259 -19.501612) (xy 435.3179 -19.501612)
				)
			)
		)
	)
	(footprint ""
		(layer "F.Cu")
		(at 407.749502 -122.823986 90)
		(property "Reference" "R1W17"
			(at -0.8382 -0.67818 90)
			(unlocked yes)
			(layer "F.SilkS")
			(effects
				(font
					(size 0.4064 0.254)
					(thickness 0.1524)
				)
				(justify left)
			)
		)
		(property "Value" ""
			(at 0 0 90)
			(layer "F.Fab")
			(effects
				(font
					(size 1.27 1.27)
				)
			)
		)
		(duplicate_pad_numbers_are_jumpers no)
		(fp_poly
			(pts
				(xy -0.2794 -0.1016) (xy 0.2794 -0.1016) (xy 0.2794 0.9906) (xy -0.2794 0.9906)
			)
			(stroke
				(width 0)
				(type default)
			)
			(fill no)
			(layer "F.CrtYd")
		)
		(fp_line
			(start 0.2794 -0.1016)
			(end -0.2794 -0.1016)
			(stroke
				(width 0.1)
				(type default)
			)
			(layer "F.Fab")
		)
		(fp_line
			(start -0.2794 -0.1016)
			(end -0.2794 0.9906)
			(stroke
				(width 0.1)
				(type default)
			)
			(layer "F.Fab")
		)
		(fp_line
			(start 0.2794 0.9906)
			(end 0.2794 -0.1016)
			(stroke
				(width 0.1)
				(type default)
			)
			(layer "F.Fab")
		)
		(fp_line
			(start -0.2794 0.9906)
			(end 0.2794 0.9906)
			(stroke
				(width 0.1)
				(type default)
			)
			(layer "F.Fab")
		)
		(pad "1" smd rect
			(at 0 0 90)
			(size 0.508 0.508)
			(layers "F.Cu" "F.Mask" "F.Paste")
			(net "USB_PCH_BMC_P4_DN_R")
		)
		(pad "2" smd rect
			(at 0 0.889 90)
			(size 0.508 0.508)
			(layers "F.Cu" "F.Mask" "F.Paste")
			(net "USB_PCH_BMC_P4_DN")
		)
		(zone
			(layer "F.Cu")
			(hatch none 0.5)
			(connect_pads
				(clearance 0)
			)
			(min_thickness 0.25)
			(keepout
				(tracks allowed)
				(vias not_allowed)
				(pads allowed)
				(copperpour not_allowed)
				(footprints allowed)
			)
			(placement
				(enabled no)
				(sheetname "")
			)
			(fill
				(thermal_gap 0.5)
				(thermal_bridge_width 0.5)
				(island_removal_mode 0)
			)
			(polygon
				(pts
					(xy 408.003502 -122.569986) (xy 408.003502 -123.077986) (xy 408.384502 -123.077986) (xy 408.384502 -122.569986)
				)
			)
		)
		(zone
			(layer "F.Cu")
			(hatch none 0.5)
			(connect_pads
				(clearance 0)
			)
			(min_thickness 0.25)
			(keepout
				(tracks not_allowed)
				(vias allowed)
				(pads allowed)
				(copperpour not_allowed)
				(footprints allowed)
			)
			(placement
				(enabled no)
				(sheetname "")
			)
			(fill
				(thermal_gap 0.5)
				(thermal_bridge_width 0.5)
				(island_removal_mode 0)
			)
			(polygon
				(pts
					(xy 408.384502 -122.569986) (xy 408.384502 -123.077986) (xy 408.003502 -123.077986) (xy 408.003502 -122.569986)
				)
			)
		)
	)
	(footprint ""
		(layer "F.Cu")
		(at 492.376714 -55.865268)
		(property "Reference" "C30W6"
			(at 0 0 0)
			(layer "F.SilkS")
			(hide yes)
			(effects
				(font
					(size 1.27 1.27)
				)
			)
		)
		(property "Value" "*"
			(at -0.0762 -6.2357 0)
			(unlocked yes)
			(layer "F.Fab")
			(hide yes)
			(effects
				(font
					(size 1.27 1.016)
					(thickness 0.1524)
				)
			)
		)
		(property "Device Type" "SC22U16V5MX-4-GP_SMD-BCG5-SC22A"
			(at -0.0762 -8.2677 0)
			(unlocked yes)
			(layer "F.Fab")
			(hide yes)
			(effects
				(font
					(size 1.27 1.016)
					(thickness 0.1524)
				)
			)
		)
		(duplicate_pad_numbers_are_jumpers no)
		(fp_line
			(start 0.635 0)
			(end -0.635 0)
			(stroke
				(width 0.508)
				(type default)
			)
			(layer "F.SilkS")
		)
		(fp_rect
			(start -0.9652 1.778)
			(end 0.9652 -1.778)
			(stroke
				(width 0)
				(type default)
			)
			(fill no)
			(layer "F.CrtYd")
		)
		(fp_poly
			(pts
				(xy -0.9652 -1.778) (xy 0.9652 -1.778) (xy 0.9652 1.778) (xy -0.9652 1.778)
			)
			(stroke
				(width 0)
				(type default)
			)
			(fill no)
			(layer "F.Fab")
		)
		(pad "1" smd rect
			(at 0 -0.9652)
			(size 1.397 1.143)
			(layers "F.Cu" "F.Mask" "F.Paste")
			(net "P5V_STBY_USBC")
		)
		(pad "2" smd rect
			(at 0 0.9652)
			(size 1.397 1.143)
			(layers "F.Cu" "F.Mask" "F.Paste")
			(net "GND")
		)
	)
	(footprint ""
		(layer "F.Cu")
		(at 399.669 -155.829 180)
		(property "Reference" "C8A2"
			(at 0 0 180)
			(layer "F.SilkS")
			(hide yes)
			(effects
				(font
					(size 1.27 1.27)
				)
			)
		)
		(property "Value" ""
			(at 0 0 180)
			(layer "F.Fab")
			(effects
				(font
					(size 1.27 1.27)
				)
			)
		)
		(duplicate_pad_numbers_are_jumpers no)
		(fp_poly
			(pts
				(xy 0.3048 -0.1016) (xy 0.3048 0.9906) (xy -0.3048 0.9906) (xy -0.3048 -0.1016)
			)
			(stroke
				(width 0)
				(type default)
			)
			(fill no)
			(layer "F.CrtYd")
		)
		(fp_line
			(start 0.3048 0.9906)
			(end 0.3048 -0.1016)
			(stroke
				(width 0.1)
				(type default)
			)
			(layer "F.Fab")
		)
		(fp_line
			(start 0.3048 -0.1016)
			(end -0.3048 -0.1016)
			(stroke
				(width 0.1)
				(type default)
			)
			(layer "F.Fab")
		)
		(fp_line
			(start -0.3048 0.9906)
			(end 0.3048 0.9906)
			(stroke
				(width 0.1)
				(type default)
			)
			(layer "F.Fab")
		)
		(fp_line
			(start -0.3048 -0.1016)
			(end -0.3048 0.9906)
			(stroke
				(width 0.1)
				(type default)
			)
			(layer "F.Fab")
		)
		(pad "1" smd rect
			(at 0 0 180)
			(size 0.508 0.508)
			(layers "F.Cu" "F.Mask" "F.Paste")
			(net "VR_PVNN_PCH_AVSP")
		)
		(pad "2" smd rect
			(at 0 0.889 180)
			(size 0.508 0.508)
			(layers "F.Cu" "F.Mask" "F.Paste")
			(net "VSENSE_PVNN_PCH_STBY_AVSN")
		)
		(zone
			(layer "F.Cu")
			(hatch none 0.5)
			(connect_pads
				(clearance 0)
			)
			(min_thickness 0.25)
			(keepout
				(tracks not_allowed)
				(vias allowed)
				(pads allowed)
				(copperpour not_allowed)
				(footprints allowed)
			)
			(placement
				(enabled no)
				(sheetname "")
			)
			(fill
				(thermal_gap 0.5)
				(thermal_bridge_width 0.5)
				(island_removal_mode 0)
			)
			(polygon
				(pts
					(xy 399.923 -156.464) (xy 399.415 -156.464) (xy 399.415 -156.083) (xy 399.923 -156.083)
				)
			)
		)
		(zone
			(layer "F.Cu")
			(hatch none 0.5)
			(connect_pads
				(clearance 0)
			)
			(min_thickness 0.25)
			(keepout
				(tracks allowed)
				(vias not_allowed)
				(pads allowed)
				(copperpour not_allowed)
				(footprints allowed)
			)
			(placement
				(enabled no)
				(sheetname "")
			)
			(fill
				(thermal_gap 0.5)
				(thermal_bridge_width 0.5)
				(island_removal_mode 0)
			)
			(polygon
				(pts
					(xy 399.923 -156.083) (xy 399.415 -156.083) (xy 399.415 -156.464) (xy 399.923 -156.464)
				)
			)
		)
	)
)
